# T6G (Grand Teton) — schematic netlist excerpt (pin names and nets, part order shuffled) for the footprints in the layout excerpt that follows; sources: Cadence DE-HDL packaged netlist, KiCad conversion of 04192023_DAF0TMB3IC0_F0TG_MB_C_brd_V02_OCP.brd

R6  Q_RES  54.9K 1% CHIP  pkg 0402LF  page 102 : A = PD_CHE_CPU1_DIMM_SAA ; B = GND
C6047  Q_CAP  1UF 25V 10% X6S  pkg C0402  page 177 : A = P3V3_AUX ; B = GND
R780  Q_RES  0 5% CHIP  pkg 0201LF  page 331 : A = SMB_RT_CPU1_P1_R_SDA ; B = SMB_RT_CPU1_P1_R2_SDA

(kicad_pcb
	(version 20260206)
	(generator "pcbnew")
	(generator_version "10.0")
	(general
		(thickness 1.6)
		(legacy_teardrops no)
	)
	(paper "A4")
	(title_block
		(title "04192023_DAF0TMB3IC0_F0TG_MB_C_brd_V02_OCP.brd")
		(comment 1 "Grand Teton / footprints 8019-8021 of 8354")
	)
	(layers
		(0 "F.Cu" signal "TOP")
		(4 "In1.Cu" signal "GND")
		(6 "In2.Cu" signal "IN1")
		(8 "In3.Cu" signal "GND1")
		(10 "In4.Cu" signal "IN2")
		(12 "In5.Cu" signal "GND2")
		(14 "In6.Cu" signal "IN3")
		(16 "In7.Cu" signal "GND3")
		(18 "In8.Cu" signal "VCC")
		(20 "In9.Cu" signal "VCC1")
		(22 "In10.Cu" signal "GND4")
		(24 "In11.Cu" signal "IN4")
		(26 "In12.Cu" signal "GND5")
		(28 "In13.Cu" signal "IN5")
		(30 "In14.Cu" signal "GND6")
		(32 "In15.Cu" signal "IN6")
		(34 "In16.Cu" signal "GND7")
		(2 "B.Cu" signal "BOTTOM")
		(9 "F.Adhes" user "F.Adhesive")
		(11 "B.Adhes" user "B.Adhesive")
		(13 "F.Paste" user "Package Geometry/Pastemask Top")
		(15 "B.Paste" user "Package Geometry/Pastemask Bottom")
		(5 "F.SilkS" user "Ref Des/Silkscreen Top")
		(7 "B.SilkS" user "Ref Des/Silkscreen Bottom")
		(1 "F.Mask" user "Board Geometry/Soldermask Top")
		(3 "B.Mask" user "Board Geometry/Soldermask Bottom")
		(17 "Dwgs.User" user "User.Drawings")
		(19 "Cmts.User" user "User.Comments")
		(21 "Eco1.User" user "User.Eco1")
		(23 "Eco2.User" user "User.Eco2")
		(25 "Edge.Cuts" user "Board Geometry/Outline")
		(27 "Margin" user)
		(31 "F.CrtYd" user "Package Geometry/Place Bound Top")
		(29 "B.CrtYd" user "Package Geometry/Place Bound Bottom")
		(35 "F.Fab" user "Ref Des/Assembly Top")
		(33 "B.Fab" user "Ref Des/Assembly Bottom")
	)
	(footprint ""
		(layer "B.Cu")
		(at 25.92324 -194.885564 180)
		(property "Reference" "R6"
			(at 0 0 0)
			(layer "B.SilkS")
			(hide yes)
			(effects
				(font
					(size 1.27 1.27)
				)
				(justify mirror)
			)
		)
		(property "Value" ""
			(at 0 0 0)
			(layer "B.Fab")
			(effects
				(font
					(size 1.27 1.27)
				)
				(justify mirror)
			)
		)
		(duplicate_pad_numbers_are_jumpers no)
		(fp_line
			(start 0.7874 0.4064)
			(end 0.7874 -0.4064)
			(stroke
				(width 0.1524)
				(type default)
			)
			(layer "B.SilkS")
		)
		(fp_line
			(start 0.7874 -0.4064)
			(end -0.7874 -0.4064)
			(stroke
				(width 0.1524)
				(type default)
			)
			(layer "B.SilkS")
		)
		(fp_line
			(start -0.7874 0.4064)
			(end 0.7874 0.4064)
			(stroke
				(width 0.1524)
				(type default)
			)
			(layer "B.SilkS")
		)
		(fp_line
			(start -0.7874 -0.4064)
			(end -0.7874 0.4064)
			(stroke
				(width 0.1524)
				(type default)
			)
			(layer "B.SilkS")
		)
		(fp_line
			(start 0.67945 0.3048)
			(end 0.67945 -0.305054)
			(stroke
				(width 0.1)
				(type default)
			)
			(layer "B.Fab")
		)
		(fp_line
			(start 0.67945 -0.305054)
			(end 0.12065 -0.305054)
			(stroke
				(width 0.1)
				(type default)
			)
			(layer "B.Fab")
		)
		(fp_line
			(start 0.12065 0.3048)
			(end 0.67945 0.3048)
			(stroke
				(width 0.1)
				(type default)
			)
			(layer "B.Fab")
		)
		(fp_line
			(start 0.12065 0.2794)
			(end 0.12065 0.3048)
			(stroke
				(width 0.1)
				(type default)
			)
			(layer "B.Fab")
		)
		(fp_line
			(start 0.12065 -0.2794)
			(end -0.12065 -0.2794)
			(stroke
				(width 0.1)
				(type default)
			)
			(layer "B.Fab")
		)
		(fp_line
			(start 0.12065 -0.305054)
			(end 0.12065 -0.2794)
			(stroke
				(width 0.1)
				(type default)
			)
			(layer "B.Fab")
		)
		(fp_line
			(start -0.120396 0.3048)
			(end -0.120396 0.2794)
			(stroke
				(width 0.1)
				(type default)
			)
			(layer "B.Fab")
		)
		(fp_line
			(start -0.120396 0.2794)
			(end 0.12065 0.2794)
			(stroke
				(width 0.1)
				(type default)
			)
			(layer "B.Fab")
		)
		(fp_line
			(start -0.12065 -0.2794)
			(end -0.12065 -0.3048)
			(stroke
				(width 0.1)
				(type default)
			)
			(layer "B.Fab")
		)
		(fp_line
			(start -0.12065 -0.3048)
			(end -0.67945 -0.3048)
			(stroke
				(width 0.1)
				(type default)
			)
			(layer "B.Fab")
		)
		(fp_line
			(start -0.67945 0.3048)
			(end -0.120396 0.3048)
			(stroke
				(width 0.1)
				(type default)
			)
			(layer "B.Fab")
		)
		(fp_line
			(start -0.67945 -0.3048)
			(end -0.67945 0.3048)
			(stroke
				(width 0.1)
				(type default)
			)
			(layer "B.Fab")
		)
		(pad "1" smd circle
			(at 0.40005 0)
			(size 0 0)
			(layers "B.Cu" "B.Mask" "B.Paste")
			(net "PD_CHE_CPU1_DIMM_SAA")
		)
		(pad "2" smd circle
			(at -0.40005 0)
			(size 0 0)
			(layers "B.Cu" "B.Mask" "B.Paste")
			(net "GND")
		)
	)
	(footprint ""
		(layer "B.Cu")
		(at 215.0618 -336.296)
		(property "Reference" "R780"
			(at 0 0 0)
			(layer "B.SilkS")
			(hide yes)
			(effects
				(font
					(size 1.27 1.27)
				)
				(justify mirror)
			)
		)
		(property "Value" ""
			(at 0 0 0)
			(layer "B.Fab")
			(effects
				(font
					(size 1.27 1.27)
				)
				(justify mirror)
			)
		)
		(duplicate_pad_numbers_are_jumpers no)
		(fp_line
			(start -0.32512 -0.175006)
			(end -0.32512 0.175006)
			(stroke
				(width 0.1)
				(type default)
			)
			(layer "B.Fab")
		)
		(fp_line
			(start -0.32512 0.175006)
			(end 0.32512 0.175006)
			(stroke
				(width 0.1)
				(type default)
			)
			(layer "B.Fab")
		)
		(fp_line
			(start 0.32512 -0.175006)
			(end -0.32512 -0.175006)
			(stroke
				(width 0.1)
				(type default)
			)
			(layer "B.Fab")
		)
		(fp_line
			(start 0.32512 0.175006)
			(end 0.32512 -0.175006)
			(stroke
				(width 0.1)
				(type default)
			)
			(layer "B.Fab")
		)
		(pad "1" smd rect
			(at 0.2667 0 180)
			(size 0.3048 0.381)
			(layers "B.Cu" "B.Mask" "B.Paste")
			(net "SMB_RT_CPU1_P1_R_SDA")
		)
		(pad "2" smd rect
			(at -0.2667 0)
			(size 0.3048 0.381)
			(layers "B.Cu" "B.Mask" "B.Paste")
			(net "SMB_RT_CPU1_P1_R2_SDA")
		)
	)
	(footprint ""
		(layer "B.Cu")
		(at 136.874504 -31.874206 -90)
		(property "Reference" "C6047"
			(at 0 0 90)
			(layer "B.SilkS")
			(hide yes)
			(effects
				(font
					(size 1.27 1.27)
				)
				(justify mirror)
			)
		)
		(property "Value" ""
			(at 0 0 90)
			(layer "B.Fab")
			(effects
				(font
					(size 1.27 1.27)
				)
				(justify mirror)
			)
		)
		(duplicate_pad_numbers_are_jumpers no)
		(fp_line
			(start -0.7874 0.4064)
			(end 0.7874 0.4064)
			(stroke
				(width 0.1524)
				(type default)
			)
			(layer "B.SilkS")
		)
		(fp_line
			(start 0.7874 0.4064)
			(end 0.7874 -0.4064)
			(stroke
				(width 0.1524)
				(type default)
			)
			(layer "B.SilkS")
		)
		(fp_line
			(start -0.7874 -0.4064)
			(end -0.7874 0.4064)
			(stroke
				(width 0.1524)
				(type default)
			)
			(layer "B.SilkS")
		)
		(fp_line
			(start 0.7874 -0.4064)
			(end -0.7874 -0.4064)
			(stroke
				(width 0.1524)
				(type default)
			)
			(layer "B.SilkS")
		)
		(fp_line
			(start -0.67945 0.3048)
			(end -0.120396 0.3048)
			(stroke
				(width 0.1)
				(type default)
			)
			(layer "B.Fab")
		)
		(fp_line
			(start -0.120396 0.3048)
			(end -0.120396 0.2794)
			(stroke
				(width 0.1)
				(type default)
			)
			(layer "B.Fab")
		)
		(fp_line
			(start 0.12065 0.3048)
			(end 0.67945 0.3048)
			(stroke
				(width 0.1)
				(type default)
			)
			(layer "B.Fab")
		)
		(fp_line
			(start 0.67945 0.3048)
			(end 0.67945 -0.305054)
			(stroke
				(width 0.1)
				(type default)
			)
			(layer "B.Fab")
		)
		(fp_line
			(start -0.120396 0.2794)
			(end 0.12065 0.2794)
			(stroke
				(width 0.1)
				(type default)
			)
			(layer "B.Fab")
		)
		(fp_line
			(start 0.12065 0.2794)
			(end 0.12065 0.3048)
			(stroke
				(width 0.1)
				(type default)
			)
			(layer "B.Fab")
		)
		(fp_line
			(start -0.12065 -0.2794)
			(end -0.12065 -0.3048)
			(stroke
				(width 0.1)
				(type default)
			)
			(layer "B.Fab")
		)
		(fp_line
			(start 0.12065 -0.2794)
			(end -0.12065 -0.2794)
			(stroke
				(width 0.1)
				(type default)
			)
			(layer "B.Fab")
		)
		(fp_line
			(start -0.67945 -0.3048)
			(end -0.67945 0.3048)
			(stroke
				(width 0.1)
				(type default)
			)
			(layer "B.Fab")
		)
		(fp_line
			(start -0.12065 -0.3048)
			(end -0.67945 -0.3048)
			(stroke
				(width 0.1)
				(type default)
			)
			(layer "B.Fab")
		)
		(fp_line
			(start 0.12065 -0.305054)
			(end 0.12065 -0.2794)
			(stroke
				(width 0.1)
				(type default)
			)
			(layer "B.Fab")
		)
		(fp_line
			(start 0.67945 -0.305054)
			(end 0.12065 -0.305054)
			(stroke
				(width 0.1)
				(type default)
			)
			(layer "B.Fab")
		)
		(pad "1" smd circle
			(at 0.40005 0 90)
			(size 0 0)
			(layers "B.Cu" "B.Mask" "B.Paste")
			(net "P3V3_AUX")
		)
		(pad "2" smd circle
			(at -0.40005 0 90)
			(size 0 0)
			(layers "B.Cu" "B.Mask" "B.Paste")
			(net "GND")
		)
	)
)
